# T6G (Grand Teton) — schematic netlist excerpt (pin names and nets, part order shuffled) for the footprints in the layout excerpt that follows; sources: Cadence DE-HDL packaged netlist, KiCad conversion of 04192023_DAF0TMB3IC0_F0TG_MB_C_brd_V02_OCP.brd

R1352  Q_RES  0 5% CHIP  pkg 0402LF  page 172 : A = HDT_HDR_R_TCK ; B = HDT_HDR_TCK
R3721  Q_RES  0 5% CHIP  pkg 0402LF  page 252 : A = SMB_LM75_3_3V3AUX_SCL_R ; B = SMB_LM75_3_3V3AUX_SCL

(kicad_pcb
	(version 20260206)
	(generator "pcbnew")
	(generator_version "10.0")
	(general
		(thickness 1.6)
		(legacy_teardrops no)
	)
	(paper "A4")
	(title_block
		(title "04192023_DAF0TMB3IC0_F0TG_MB_C_brd_V02_OCP.brd")
		(comment 1 "Grand Teton / footprints 98-99 of 8354")
	)
	(layers
		(0 "F.Cu" signal "TOP")
		(4 "In1.Cu" signal "GND")
		(6 "In2.Cu" signal "IN1")
		(8 "In3.Cu" signal "GND1")
		(10 "In4.Cu" signal "IN2")
		(12 "In5.Cu" signal "GND2")
		(14 "In6.Cu" signal "IN3")
		(16 "In7.Cu" signal "GND3")
		(18 "In8.Cu" signal "VCC")
		(20 "In9.Cu" signal "VCC1")
		(22 "In10.Cu" signal "GND4")
		(24 "In11.Cu" signal "IN4")
		(26 "In12.Cu" signal "GND5")
		(28 "In13.Cu" signal "IN5")
		(30 "In14.Cu" signal "GND6")
		(32 "In15.Cu" signal "IN6")
		(34 "In16.Cu" signal "GND7")
		(2 "B.Cu" signal "BOTTOM")
		(9 "F.Adhes" user "F.Adhesive")
		(11 "B.Adhes" user "B.Adhesive")
		(13 "F.Paste" user "Package Geometry/Pastemask Top")
		(15 "B.Paste" user "Package Geometry/Pastemask Bottom")
		(5 "F.SilkS" user "Ref Des/Silkscreen Top")
		(7 "B.SilkS" user "Ref Des/Silkscreen Bottom")
		(1 "F.Mask" user "Board Geometry/Soldermask Top")
		(3 "B.Mask" user "Board Geometry/Soldermask Bottom")
		(17 "Dwgs.User" user "User.Drawings")
		(19 "Cmts.User" user "User.Comments")
		(21 "Eco1.User" user "User.Eco1")
		(23 "Eco2.User" user "User.Eco2")
		(25 "Edge.Cuts" user "Board Geometry/Outline")
		(27 "Margin" user)
		(31 "F.CrtYd" user "Package Geometry/Place Bound Top")
		(29 "B.CrtYd" user "Package Geometry/Place Bound Bottom")
		(35 "F.Fab" user "Ref Des/Assembly Top")
		(33 "B.Fab" user "Ref Des/Assembly Bottom")
	)
	(footprint ""
		(layer "F.Cu")
		(at 386.211826 -53.1495 180)
		(property "Reference" "R1352"
			(at 0 0 180)
			(layer "F.SilkS")
			(hide yes)
			(effects
				(font
					(size 1.27 1.27)
				)
			)
		)
		(property "Value" ""
			(at 0 0 180)
			(layer "F.Fab")
			(effects
				(font
					(size 1.27 1.27)
				)
			)
		)
		(duplicate_pad_numbers_are_jumpers no)
		(fp_line
			(start 0.7874 0.4064)
			(end -0.7874 0.4064)
			(stroke
				(width 0.1524)
				(type default)
			)
			(layer "F.SilkS")
		)
		(fp_line
			(start 0.7874 -0.4064)
			(end 0.7874 0.4064)
			(stroke
				(width 0.1524)
				(type default)
			)
			(layer "F.SilkS")
		)
		(fp_line
			(start -0.7874 0.4064)
			(end -0.7874 -0.4064)
			(stroke
				(width 0.1524)
				(type default)
			)
			(layer "F.SilkS")
		)
		(fp_line
			(start -0.7874 -0.4064)
			(end 0.7874 -0.4064)
			(stroke
				(width 0.1524)
				(type default)
			)
			(layer "F.SilkS")
		)
		(fp_line
			(start 0.67945 0.3048)
			(end 0.120396 0.3048)
			(stroke
				(width 0.1)
				(type default)
			)
			(layer "F.Fab")
		)
		(fp_line
			(start 0.67945 -0.3048)
			(end 0.67945 0.3048)
			(stroke
				(width 0.1)
				(type default)
			)
			(layer "F.Fab")
		)
		(fp_line
			(start 0.12065 -0.2794)
			(end 0.12065 -0.3048)
			(stroke
				(width 0.1)
				(type default)
			)
			(layer "F.Fab")
		)
		(fp_line
			(start 0.12065 -0.3048)
			(end 0.67945 -0.3048)
			(stroke
				(width 0.1)
				(type default)
			)
			(layer "F.Fab")
		)
		(fp_line
			(start 0.120396 0.3048)
			(end 0.120396 0.2794)
			(stroke
				(width 0.1)
				(type default)
			)
			(layer "F.Fab")
		)
		(fp_line
			(start 0.120396 0.2794)
			(end -0.12065 0.2794)
			(stroke
				(width 0.1)
				(type default)
			)
			(layer "F.Fab")
		)
		(fp_line
			(start -0.12065 0.3048)
			(end -0.67945 0.3048)
			(stroke
				(width 0.1)
				(type default)
			)
			(layer "F.Fab")
		)
		(fp_line
			(start -0.12065 0.2794)
			(end -0.12065 0.3048)
			(stroke
				(width 0.1)
				(type default)
			)
			(layer "F.Fab")
		)
		(fp_line
			(start -0.12065 -0.2794)
			(end 0.12065 -0.2794)
			(stroke
				(width 0.1)
				(type default)
			)
			(layer "F.Fab")
		)
		(fp_line
			(start -0.12065 -0.305054)
			(end -0.12065 -0.2794)
			(stroke
				(width 0.1)
				(type default)
			)
			(layer "F.Fab")
		)
		(fp_line
			(start -0.67945 0.3048)
			(end -0.67945 -0.305054)
			(stroke
				(width 0.1)
				(type default)
			)
			(layer "F.Fab")
		)
		(fp_line
			(start -0.67945 -0.305054)
			(end -0.12065 -0.305054)
			(stroke
				(width 0.1)
				(type default)
			)
			(layer "F.Fab")
		)
		(pad "1" smd circle
			(at -0.40005 0 180)
			(size 0 0)
			(layers "F.Cu" "F.Mask" "F.Paste")
			(net "HDT_HDR_R_TCK")
		)
		(pad "2" smd circle
			(at 0.40005 0 180)
			(size 0 0)
			(layers "F.Cu" "F.Mask" "F.Paste")
			(net "HDT_HDR_TCK")
		)
	)
	(footprint ""
		(layer "F.Cu")
		(at 271.085056 -115.22837)
		(property "Reference" "R3721"
			(at 0 0 0)
			(layer "F.SilkS")
			(hide yes)
			(effects
				(font
					(size 1.27 1.27)
				)
			)
		)
		(property "Value" ""
			(at 0 0 0)
			(layer "F.Fab")
			(effects
				(font
					(size 1.27 1.27)
				)
			)
		)
		(duplicate_pad_numbers_are_jumpers no)
		(fp_line
			(start -0.7874 -0.4064)
			(end 0.7874 -0.4064)
			(stroke
				(width 0.1524)
				(type default)
			)
			(layer "F.SilkS")
		)
		(fp_line
			(start -0.7874 0.4064)
			(end -0.7874 -0.4064)
			(stroke
				(width 0.1524)
				(type default)
			)
			(layer "F.SilkS")
		)
		(fp_line
			(start 0.7874 -0.4064)
			(end 0.7874 0.4064)
			(stroke
				(width 0.1524)
				(type default)
			)
			(layer "F.SilkS")
		)
		(fp_line
			(start 0.7874 0.4064)
			(end -0.7874 0.4064)
			(stroke
				(width 0.1524)
				(type default)
			)
			(layer "F.SilkS")
		)
		(fp_line
			(start -0.67945 -0.305054)
			(end -0.12065 -0.305054)
			(stroke
				(width 0.1)
				(type default)
			)
			(layer "F.Fab")
		)
		(fp_line
			(start -0.67945 0.3048)
			(end -0.67945 -0.305054)
			(stroke
				(width 0.1)
				(type default)
			)
			(layer "F.Fab")
		)
		(fp_line
			(start -0.12065 -0.305054)
			(end -0.12065 -0.2794)
			(stroke
				(width 0.1)
				(type default)
			)
			(layer "F.Fab")
		)
		(fp_line
			(start -0.12065 -0.2794)
			(end 0.12065 -0.2794)
			(stroke
				(width 0.1)
				(type default)
			)
			(layer "F.Fab")
		)
		(fp_line
			(start -0.12065 0.2794)
			(end -0.12065 0.3048)
			(stroke
				(width 0.1)
				(type default)
			)
			(layer "F.Fab")
		)
		(fp_line
			(start -0.12065 0.3048)
			(end -0.67945 0.3048)
			(stroke
				(width 0.1)
				(type default)
			)
			(layer "F.Fab")
		)
		(fp_line
			(start 0.120396 0.2794)
			(end -0.12065 0.2794)
			(stroke
				(width 0.1)
				(type default)
			)
			(layer "F.Fab")
		)
		(fp_line
			(start 0.120396 0.3048)
			(end 0.120396 0.2794)
			(stroke
				(width 0.1)
				(type default)
			)
			(layer "F.Fab")
		)
		(fp_line
			(start 0.12065 -0.3048)
			(end 0.67945 -0.3048)
			(stroke
				(width 0.1)
				(type default)
			)
			(layer "F.Fab")
		)
		(fp_line
			(start 0.12065 -0.2794)
			(end 0.12065 -0.3048)
			(stroke
				(width 0.1)
				(type default)
			)
			(layer "F.Fab")
		)
		(fp_line
			(start 0.67945 -0.3048)
			(end 0.67945 0.3048)
			(stroke
				(width 0.1)
				(type default)
			)
			(layer "F.Fab")
		)
		(fp_line
			(start 0.67945 0.3048)
			(end 0.120396 0.3048)
			(stroke
				(width 0.1)
				(type default)
			)
			(layer "F.Fab")
		)
		(pad "1" smd circle
			(at -0.40005 0)
			(size 0 0)
			(layers "F.Cu" "F.Mask" "F.Paste")
			(net "SMB_LM75_3_3V3AUX_SCL_R")
		)
		(pad "2" smd circle
			(at 0.40005 0)
			(size 0 0)
			(layers "F.Cu" "F.Mask" "F.Paste")
			(net "SMB_LM75_3_3V3AUX_SCL")
		)
	)
)
